# S9S_MB_2U (Grand Teton) — schematic netlist excerpt (pin names and nets, part order shuffled) for the footprints in the layout excerpt that follows; sources: Cadence DE-HDL packaged netlist, KiCad conversion of 03242023_DA0F0TMBIJ0_F0T_Motherboard_J_brd_V01_OCP.brd

PR338  Q_RES  0 5% CHIP  pkg 0402LF  page 262 : A = P1V05_PCH_AUX_MODE ; B = GND
C1929  Q_CAP  0.01UF 50V 10% X7R  pkg C0402  page 217 : A = P3V3_AUX_FPGA_VCCIO0 ; B = GND
PC2280  Q_CAP  10UF 16V 10% X6S  pkg C0805  page 192 : A = P12V_E1S_0 ; B = GND

(kicad_pcb
	(version 20260206)
	(generator "pcbnew")
	(generator_version "10.0")
	(general
		(thickness 1.6)
		(legacy_teardrops no)
	)
	(paper "A4")
	(title_block
		(title "03242023_DA0F0TMBIJ0_F0T_Motherboard_J_brd_V01_OCP.brd")
		(comment 1 "Grand Teton / footprints 5385-5387 of 6105")
	)
	(layers
		(0 "F.Cu" signal "TOP")
		(4 "In1.Cu" signal "GND")
		(6 "In2.Cu" signal "IN1")
		(8 "In3.Cu" signal "GND1")
		(10 "In4.Cu" signal "IN2")
		(12 "In5.Cu" signal "GND2")
		(14 "In6.Cu" signal "IN3")
		(16 "In7.Cu" signal "GND3")
		(18 "In8.Cu" signal "VCC")
		(20 "In9.Cu" signal "VCC1")
		(22 "In10.Cu" signal "GND4")
		(24 "In11.Cu" signal "IN4")
		(26 "In12.Cu" signal "GND5")
		(28 "In13.Cu" signal "IN5")
		(30 "In14.Cu" signal "GND6")
		(32 "In15.Cu" signal "IN6")
		(34 "In16.Cu" signal "GND7")
		(2 "B.Cu" signal "BOTTOM")
		(9 "F.Adhes" user "F.Adhesive")
		(11 "B.Adhes" user "B.Adhesive")
		(13 "F.Paste" user "Package Geometry/Pastemask Top")
		(15 "B.Paste" user "Package Geometry/Pastemask Bottom")
		(5 "F.SilkS" user "Ref Des/Silkscreen Top")
		(7 "B.SilkS" user "Ref Des/Silkscreen Bottom")
		(1 "F.Mask" user "Board Geometry/Soldermask Top")
		(3 "B.Mask" user "Board Geometry/Soldermask Bottom")
		(17 "Dwgs.User" user "User.Drawings")
		(19 "Cmts.User" user "User.Comments")
		(21 "Eco1.User" user "User.Eco1")
		(23 "Eco2.User" user "User.Eco2")
		(25 "Edge.Cuts" user "Board Geometry/Outline")
		(27 "Margin" user)
		(31 "F.CrtYd" user "Package Geometry/Place Bound Top")
		(29 "B.CrtYd" user "Package Geometry/Place Bound Bottom")
		(35 "F.Fab" user "Ref Des/Assembly Top")
		(33 "B.Fab" user "Ref Des/Assembly Bottom")
	)
	(footprint ""
		(layer "B.Cu")
		(at 175.355758 -113.77549 180)
		(property "Reference" "C1929"
			(at 0 0 0)
			(layer "B.SilkS")
			(hide yes)
			(effects
				(font
					(size 1.27 1.27)
				)
				(justify mirror)
			)
		)
		(property "Value" ""
			(at 0 0 0)
			(layer "B.Fab")
			(effects
				(font
					(size 1.27 1.27)
				)
				(justify mirror)
			)
		)
		(duplicate_pad_numbers_are_jumpers no)
		(fp_line
			(start 0.69215 0.2921)
			(end 0.69215 -0.2921)
			(stroke
				(width 0.1524)
				(type default)
			)
			(layer "B.SilkS")
		)
		(fp_line
			(start 0.69215 -0.2921)
			(end -0.69215 -0.2921)
			(stroke
				(width 0.1524)
				(type default)
			)
			(layer "B.SilkS")
		)
		(fp_line
			(start -0.69215 0.2921)
			(end 0.69215 0.2921)
			(stroke
				(width 0.1524)
				(type default)
			)
			(layer "B.SilkS")
		)
		(fp_line
			(start -0.69215 -0.2921)
			(end -0.69215 0.2921)
			(stroke
				(width 0.1524)
				(type default)
			)
			(layer "B.SilkS")
		)
		(fp_line
			(start 0.51435 0.2794)
			(end 0.51435 -0.2794)
			(stroke
				(width 0.1)
				(type default)
			)
			(layer "B.Fab")
		)
		(fp_line
			(start 0.51435 -0.2794)
			(end -0.51435 -0.2794)
			(stroke
				(width 0.1)
				(type default)
			)
			(layer "B.Fab")
		)
		(fp_line
			(start -0.51435 0.2794)
			(end 0.51435 0.2794)
			(stroke
				(width 0.1)
				(type default)
			)
			(layer "B.Fab")
		)
		(fp_line
			(start -0.51435 -0.2794)
			(end -0.51435 0.2794)
			(stroke
				(width 0.1)
				(type default)
			)
			(layer "B.Fab")
		)
		(pad "1" smd circle
			(at 0.40005 0)
			(size 0 0)
			(layers "B.Cu" "B.Mask" "B.Paste")
			(net "P3V3_AUX_FPGA_VCCIO0")
		)
		(pad "2" smd circle
			(at -0.40005 0)
			(size 0 0)
			(layers "B.Cu" "B.Mask" "B.Paste")
			(net "GND")
		)
		(zone
			(layer "B.Cu")
			(hatch none 0.5)
			(connect_pads
				(clearance 0)
			)
			(min_thickness 0.25)
			(keepout
				(tracks not_allowed)
				(vias allowed)
				(pads allowed)
				(copperpour not_allowed)
				(footprints allowed)
			)
			(placement
				(enabled no)
				(sheetname "")
			)
			(fill
				(thermal_gap 0.5)
				(thermal_bridge_width 0.5)
				(island_removal_mode 0)
			)
			(polygon
				(pts
					(xy 175.165258 -113.86312) (xy 175.256698 -113.921286) (xy 175.456088 -113.921286) (xy 175.546258 -113.86312)
					(xy 175.546258 -113.68786) (xy 175.456088 -113.62944) (xy 175.256698 -113.62944) (xy 175.165258 -113.687606)
				)
			)
		)
	)
	(footprint ""
		(layer "B.Cu")
		(at 263.398 -74.933048 90)
		(property "Reference" "PR338"
			(at 0 0 90)
			(layer "B.SilkS")
			(hide yes)
			(effects
				(font
					(size 1.27 1.27)
				)
				(justify mirror)
			)
		)
		(property "Value" ""
			(at 0 0 90)
			(layer "B.Fab")
			(effects
				(font
					(size 1.27 1.27)
				)
				(justify mirror)
			)
		)
		(duplicate_pad_numbers_are_jumpers no)
		(fp_line
			(start 0.7874 -0.4064)
			(end -0.7874 -0.4064)
			(stroke
				(width 0.1524)
				(type default)
			)
			(layer "B.SilkS")
		)
		(fp_line
			(start -0.7874 -0.4064)
			(end -0.7874 0.4064)
			(stroke
				(width 0.1524)
				(type default)
			)
			(layer "B.SilkS")
		)
		(fp_line
			(start 0.7874 0.4064)
			(end 0.7874 -0.4064)
			(stroke
				(width 0.1524)
				(type default)
			)
			(layer "B.SilkS")
		)
		(fp_line
			(start -0.7874 0.4064)
			(end 0.7874 0.4064)
			(stroke
				(width 0.1524)
				(type default)
			)
			(layer "B.SilkS")
		)
		(fp_line
			(start 0.67945 -0.305054)
			(end 0.12065 -0.305054)
			(stroke
				(width 0.1)
				(type default)
			)
			(layer "B.Fab")
		)
		(fp_line
			(start 0.12065 -0.305054)
			(end 0.12065 -0.2794)
			(stroke
				(width 0.1)
				(type default)
			)
			(layer "B.Fab")
		)
		(fp_line
			(start -0.12065 -0.3048)
			(end -0.67945 -0.3048)
			(stroke
				(width 0.1)
				(type default)
			)
			(layer "B.Fab")
		)
		(fp_line
			(start -0.67945 -0.3048)
			(end -0.67945 0.3048)
			(stroke
				(width 0.1)
				(type default)
			)
			(layer "B.Fab")
		)
		(fp_line
			(start 0.12065 -0.2794)
			(end -0.12065 -0.2794)
			(stroke
				(width 0.1)
				(type default)
			)
			(layer "B.Fab")
		)
		(fp_line
			(start -0.12065 -0.2794)
			(end -0.12065 -0.3048)
			(stroke
				(width 0.1)
				(type default)
			)
			(layer "B.Fab")
		)
		(fp_line
			(start 0.12065 0.2794)
			(end 0.12065 0.3048)
			(stroke
				(width 0.1)
				(type default)
			)
			(layer "B.Fab")
		)
		(fp_line
			(start -0.120396 0.2794)
			(end 0.12065 0.2794)
			(stroke
				(width 0.1)
				(type default)
			)
			(layer "B.Fab")
		)
		(fp_line
			(start 0.67945 0.3048)
			(end 0.67945 -0.305054)
			(stroke
				(width 0.1)
				(type default)
			)
			(layer "B.Fab")
		)
		(fp_line
			(start 0.12065 0.3048)
			(end 0.67945 0.3048)
			(stroke
				(width 0.1)
				(type default)
			)
			(layer "B.Fab")
		)
		(fp_line
			(start -0.120396 0.3048)
			(end -0.120396 0.2794)
			(stroke
				(width 0.1)
				(type default)
			)
			(layer "B.Fab")
		)
		(fp_line
			(start -0.67945 0.3048)
			(end -0.120396 0.3048)
			(stroke
				(width 0.1)
				(type default)
			)
			(layer "B.Fab")
		)
		(pad "1" smd circle
			(at 0.40005 0 270)
			(size 0 0)
			(layers "B.Cu" "B.Mask" "B.Paste")
			(net "P1V05_PCH_AUX_MODE")
		)
		(pad "2" smd circle
			(at -0.40005 0 270)
			(size 0 0)
			(layers "B.Cu" "B.Mask" "B.Paste")
			(net "GND")
		)
	)
	(footprint ""
		(layer "B.Cu")
		(at 246.01932 -52.907946 -90)
		(property "Reference" "PC2280"
			(at 0 0 90)
			(layer "B.SilkS")
			(hide yes)
			(effects
				(font
					(size 1.27 1.27)
				)
				(justify mirror)
			)
		)
		(property "Value" ""
			(at 0 0 90)
			(layer "B.Fab")
			(effects
				(font
					(size 1.27 1.27)
				)
				(justify mirror)
			)
		)
		(duplicate_pad_numbers_are_jumpers no)
		(fp_line
			(start -1.524 0.762)
			(end 1.524 0.762)
			(stroke
				(width 0.1524)
				(type default)
			)
			(layer "B.SilkS")
		)
		(fp_line
			(start 1.524 0.762)
			(end 1.524 -0.762)
			(stroke
				(width 0.1524)
				(type default)
			)
			(layer "B.SilkS")
		)
		(fp_line
			(start -1.524 -0.762)
			(end -1.524 0.762)
			(stroke
				(width 0.1524)
				(type default)
			)
			(layer "B.SilkS")
		)
		(fp_line
			(start 1.524 -0.762)
			(end -1.524 -0.762)
			(stroke
				(width 0.1524)
				(type default)
			)
			(layer "B.SilkS")
		)
		(fp_line
			(start -1.1049 0.724916)
			(end -1.1049 -0.724916)
			(stroke
				(width 0.1)
				(type default)
			)
			(layer "B.Fab")
		)
		(fp_line
			(start 1.1049 0.724916)
			(end -1.1049 0.724916)
			(stroke
				(width 0.1)
				(type default)
			)
			(layer "B.Fab")
		)
		(fp_line
			(start -1.1049 -0.724916)
			(end 1.1049 -0.724916)
			(stroke
				(width 0.1)
				(type default)
			)
			(layer "B.Fab")
		)
		(fp_line
			(start 1.1049 -0.724916)
			(end 1.1049 0.724916)
			(stroke
				(width 0.1)
				(type default)
			)
			(layer "B.Fab")
		)
		(pad "1" smd rect
			(at 0.889 0 270)
			(size 1.016 1.27)
			(layers "B.Cu" "B.Mask" "B.Paste")
			(net "P12V_E1S_0")
		)
		(pad "2" smd rect
			(at -0.889 0 270)
			(size 1.016 1.27)
			(layers "B.Cu" "B.Mask" "B.Paste")
			(net "GND")
		)
	)
)
